(kicad_pcb
	(version 20260206)
	(generator "pcbnew")
	(generator_version "10.0")
	(general
		(thickness 1.6)
		(legacy_teardrops no)
	)
	(paper "A4")
	(title_block
		(title "Wiwynn_Tioga_Pass_MB.brd")
		(comment 1 "Tioga Pass / footprints 3298-3304 of 4770")
	)
	(layers
		(0 "F.Cu" signal "TOP")
		(4 "In1.Cu" signal "L2GND")
		(6 "In2.Cu" signal "L3")
		(8 "In3.Cu" signal "L4GND")
		(10 "In4.Cu" signal "L5")
		(12 "In5.Cu" signal "L6GND")
		(14 "In6.Cu" signal "L7VCC")
		(16 "In7.Cu" signal "L8VCC")
		(18 "In8.Cu" signal "L9GND")
		(20 "In9.Cu" signal "L10")
		(22 "In10.Cu" signal "L11GND")
		(24 "In11.Cu" signal "L12")
		(26 "In12.Cu" signal "L13GND")
		(2 "B.Cu" signal "BOTTOM")
		(9 "F.Adhes" user "F.Adhesive")
		(11 "B.Adhes" user "B.Adhesive")
		(13 "F.Paste" user "Package Geometry/Pastemask Top")
		(15 "B.Paste" user "Package Geometry/Pastemask Bottom")
		(5 "F.SilkS" user "Ref Des/Silkscreen Top")
		(7 "B.SilkS" user "Ref Des/Silkscreen Bottom")
		(1 "F.Mask" user "Board Geometry/Soldermask Top")
		(3 "B.Mask" user "Board Geometry/Soldermask Bottom")
		(17 "Dwgs.User" user "User.Drawings")
		(19 "Cmts.User" user "User.Comments")
		(21 "Eco1.User" user "User.Eco1")
		(23 "Eco2.User" user "User.Eco2")
		(25 "Edge.Cuts" user "Board Geometry/Outline")
		(27 "Margin" user)
		(31 "F.CrtYd" user "Package Geometry/Place Bound Top")
		(29 "B.CrtYd" user "Package Geometry/Place Bound Bottom")
		(35 "F.Fab" user "Ref Des/Assembly Top")
		(33 "B.Fab" user "Ref Des/Assembly Bottom")
	)
	(footprint ""
		(layer "B.Cu")
		(at 411.503368 -39.63797 -90)
		(property "Reference" "C25W42"
			(at 0.8382 -0.67818 270)
			(unlocked yes)
			(layer "B.SilkS")
			(effects
				(font
					(size 0.4064 0.254)
					(thickness 0.1524)
				)
				(justify left mirror)
			)
		)
		(property "Value" ""
			(at 0 0 90)
			(layer "B.Fab")
			(effects
				(font
					(size 1.27 1.27)
				)
				(justify mirror)
			)
		)
		(duplicate_pad_numbers_are_jumpers no)
		(fp_poly
			(pts
				(xy -0.3048 -0.1016) (xy -0.3048 0.9906) (xy 0.3048 0.9906) (xy 0.3048 -0.1016)
			)
			(stroke
				(width 0)
				(type default)
			)
			(fill no)
			(layer "B.CrtYd")
		)
		(fp_line
			(start -0.3048 0.9906)
			(end -0.3048 -0.1016)
			(stroke
				(width 0.1)
				(type default)
			)
			(layer "B.Fab")
		)
		(fp_line
			(start 0.3048 0.9906)
			(end -0.3048 0.9906)
			(stroke
				(width 0.1)
				(type default)
			)
			(layer "B.Fab")
		)
		(fp_line
			(start -0.3048 -0.1016)
			(end 0.3048 -0.1016)
			(stroke
				(width 0.1)
				(type default)
			)
			(layer "B.Fab")
		)
		(fp_line
			(start 0.3048 -0.1016)
			(end 0.3048 0.9906)
			(stroke
				(width 0.1)
				(type default)
			)
			(layer "B.Fab")
		)
		(pad "1" smd rect
			(at 0 0 90)
			(size 0.508 0.508)
			(layers "B.Cu" "B.Mask" "B.Paste")
			(net "VCC_D_3V3")
		)
		(pad "2" smd rect
			(at 0 0.889 90)
			(size 0.508 0.508)
			(layers "B.Cu" "B.Mask" "B.Paste")
			(net "GND")
		)
		(zone
			(layer "B.Cu")
			(hatch none 0.5)
			(connect_pads
				(clearance 0)
			)
			(min_thickness 0.25)
			(keepout
				(tracks not_allowed)
				(vias allowed)
				(pads allowed)
				(copperpour not_allowed)
				(footprints allowed)
			)
			(placement
				(enabled no)
				(sheetname "")
			)
			(fill
				(thermal_gap 0.5)
				(thermal_bridge_width 0.5)
				(island_removal_mode 0)
			)
			(polygon
				(pts
					(xy 410.868368 -39.38397) (xy 410.868368 -39.89197) (xy 411.249368 -39.89197) (xy 411.249368 -39.38397)
				)
			)
		)
		(zone
			(layer "B.Cu")
			(hatch none 0.5)
			(connect_pads
				(clearance 0)
			)
			(min_thickness 0.25)
			(keepout
				(tracks allowed)
				(vias not_allowed)
				(pads allowed)
				(copperpour not_allowed)
				(footprints allowed)
			)
			(placement
				(enabled no)
				(sheetname "")
			)
			(fill
				(thermal_gap 0.5)
				(thermal_bridge_width 0.5)
				(island_removal_mode 0)
			)
			(polygon
				(pts
					(xy 411.249368 -39.38397) (xy 411.249368 -39.89197) (xy 410.868368 -39.89197) (xy 410.868368 -39.38397)
				)
			)
		)
	)
	(footprint ""
		(layer "B.Cu")
		(at 245.7577 -145.0086 -90)
		(property "Reference" "C5L13"
			(at -1.848866 0.752348 270)
			(unlocked yes)
			(layer "B.SilkS")
			(effects
				(font
					(size 1.27 0.9652)
					(thickness 0.1524)
				)
				(justify mirror)
			)
		)
		(property "Value" ""
			(at 0 0 90)
			(layer "B.Fab")
			(effects
				(font
					(size 1.27 1.27)
				)
				(justify mirror)
			)
		)
		(duplicate_pad_numbers_are_jumpers no)
		(fp_rect
			(start 0.500126 1.598422)
			(end -0.500126 -0.201422)
			(stroke
				(width 0)
				(type default)
			)
			(fill no)
			(layer "B.CrtYd")
		)
		(fp_line
			(start -0.500126 1.598422)
			(end 0.500126 1.598422)
			(stroke
				(width 0.1)
				(type default)
			)
			(layer "B.Fab")
		)
		(fp_line
			(start 0.500126 1.598422)
			(end 0.500126 -0.201422)
			(stroke
				(width 0.1)
				(type default)
			)
			(layer "B.Fab")
		)
		(fp_line
			(start -0.500126 -0.201422)
			(end -0.500126 1.598422)
			(stroke
				(width 0.1)
				(type default)
			)
			(layer "B.Fab")
		)
		(fp_line
			(start 0.500126 -0.201422)
			(end -0.500126 -0.201422)
			(stroke
				(width 0.1)
				(type default)
			)
			(layer "B.Fab")
		)
		(pad "1" smd rect
			(at 0 0 180)
			(size 0.889 0.9906)
			(layers "B.Cu" "B.Mask" "B.Paste")
			(net "PVDDQ_DEF")
		)
		(pad "2" smd rect
			(at 0 1.397 180)
			(size 0.889 0.9906)
			(layers "B.Cu" "B.Mask" "B.Paste")
			(net "GND")
		)
		(zone
			(layer "B.Cu")
			(hatch none 0.5)
			(connect_pads
				(clearance 0)
			)
			(min_thickness 0.25)
			(keepout
				(tracks allowed)
				(vias not_allowed)
				(pads allowed)
				(copperpour not_allowed)
				(footprints allowed)
			)
			(placement
				(enabled no)
				(sheetname "")
			)
			(fill
				(thermal_gap 0.5)
				(thermal_bridge_width 0.5)
				(island_removal_mode 0)
			)
			(polygon
				(pts
					(xy 244.8052 -144.5133) (xy 245.3132 -144.5133) (xy 245.3132 -145.5039) (xy 244.8052 -145.5039)
				)
			)
		)
		(zone
			(layer "B.Cu")
			(hatch none 0.5)
			(connect_pads
				(clearance 0)
			)
			(min_thickness 0.25)
			(keepout
				(tracks not_allowed)
				(vias allowed)
				(pads allowed)
				(copperpour not_allowed)
				(footprints allowed)
			)
			(placement
				(enabled no)
				(sheetname "")
			)
			(fill
				(thermal_gap 0.5)
				(thermal_bridge_width 0.5)
				(island_removal_mode 0)
			)
			(polygon
				(pts
					(xy 244.8052 -144.5133) (xy 245.3132 -144.5133) (xy 245.3132 -145.5039) (xy 244.8052 -145.5039)
				)
			)
		)
	)
	(footprint ""
		(layer "B.Cu")
		(at 363.4486 -62.6999 180)
		(property "Reference" "C3P50"
			(at 0 0 0)
			(layer "B.SilkS")
			(hide yes)
			(effects
				(font
					(size 1.27 1.27)
				)
				(justify mirror)
			)
		)
		(property "Value" ""
			(at 0 0 0)
			(layer "B.Fab")
			(effects
				(font
					(size 1.27 1.27)
				)
				(justify mirror)
			)
		)
		(duplicate_pad_numbers_are_jumpers no)
		(fp_poly
			(pts
				(xy -0.3048 -0.1016) (xy -0.3048 0.9906) (xy 0.3048 0.9906) (xy 0.3048 -0.1016)
			)
			(stroke
				(width 0)
				(type default)
			)
			(fill no)
			(layer "B.CrtYd")
		)
		(fp_line
			(start 0.3048 0.9906)
			(end -0.3048 0.9906)
			(stroke
				(width 0.1)
				(type default)
			)
			(layer "B.Fab")
		)
		(fp_line
			(start 0.3048 -0.1016)
			(end 0.3048 0.9906)
			(stroke
				(width 0.1)
				(type default)
			)
			(layer "B.Fab")
		)
		(fp_line
			(start -0.3048 0.9906)
			(end -0.3048 -0.1016)
			(stroke
				(width 0.1)
				(type default)
			)
			(layer "B.Fab")
		)
		(fp_line
			(start -0.3048 -0.1016)
			(end 0.3048 -0.1016)
			(stroke
				(width 0.1)
				(type default)
			)
			(layer "B.Fab")
		)
		(pad "1" smd rect
			(at 0 0)
			(size 0.508 0.508)
			(layers "B.Cu" "B.Mask" "B.Paste")
			(net "P3V3")
		)
		(pad "2" smd rect
			(at 0 0.889)
			(size 0.508 0.508)
			(layers "B.Cu" "B.Mask" "B.Paste")
			(net "GND")
		)
		(zone
			(layer "B.Cu")
			(hatch none 0.5)
			(connect_pads
				(clearance 0)
			)
			(min_thickness 0.25)
			(keepout
				(tracks not_allowed)
				(vias allowed)
				(pads allowed)
				(copperpour not_allowed)
				(footprints allowed)
			)
			(placement
				(enabled no)
				(sheetname "")
			)
			(fill
				(thermal_gap 0.5)
				(thermal_bridge_width 0.5)
				(island_removal_mode 0)
			)
			(polygon
				(pts
					(xy 363.1946 -63.3349) (xy 363.7026 -63.3349) (xy 363.7026 -62.9539) (xy 363.1946 -62.9539)
				)
			)
		)
		(zone
			(layer "B.Cu")
			(hatch none 0.5)
			(connect_pads
				(clearance 0)
			)
			(min_thickness 0.25)
			(keepout
				(tracks allowed)
				(vias not_allowed)
				(pads allowed)
				(copperpour not_allowed)
				(footprints allowed)
			)
			(placement
				(enabled no)
				(sheetname "")
			)
			(fill
				(thermal_gap 0.5)
				(thermal_bridge_width 0.5)
				(island_removal_mode 0)
			)
			(polygon
				(pts
					(xy 363.1946 -62.9539) (xy 363.7026 -62.9539) (xy 363.7026 -63.3349) (xy 363.1946 -63.3349)
				)
			)
		)
	)
	(footprint ""
		(layer "B.Cu")
		(at 409.1305 -19.812 90)
		(property "Reference" "R1U29"
			(at 0 0 90)
			(layer "B.SilkS")
			(hide yes)
			(effects
				(font
					(size 1.27 1.27)
				)
				(justify mirror)
			)
		)
		(property "Value" ""
			(at 0 0 90)
			(layer "B.Fab")
			(effects
				(font
					(size 1.27 1.27)
				)
				(justify mirror)
			)
		)
		(duplicate_pad_numbers_are_jumpers no)
		(fp_poly
			(pts
				(xy 0.2794 -0.1016) (xy -0.2794 -0.1016) (xy -0.2794 0.9906) (xy 0.2794 0.9906)
			)
			(stroke
				(width 0)
				(type default)
			)
			(fill no)
			(layer "B.CrtYd")
		)
		(fp_line
			(start 0.2794 -0.1016)
			(end 0.2794 0.9906)
			(stroke
				(width 0.1)
				(type default)
			)
			(layer "B.Fab")
		)
		(fp_line
			(start -0.2794 -0.1016)
			(end 0.2794 -0.1016)
			(stroke
				(width 0.1)
				(type default)
			)
			(layer "B.Fab")
		)
		(fp_line
			(start 0.2794 0.9906)
			(end -0.2794 0.9906)
			(stroke
				(width 0.1)
				(type default)
			)
			(layer "B.Fab")
		)
		(fp_line
			(start -0.2794 0.9906)
			(end -0.2794 -0.1016)
			(stroke
				(width 0.1)
				(type default)
			)
			(layer "B.Fab")
		)
		(pad "1" smd rect
			(at 0 0 270)
			(size 0.508 0.508)
			(layers "B.Cu" "B.Mask" "B.Paste")
			(net "P5V")
		)
		(pad "2" smd rect
			(at 0 0.889 270)
			(size 0.508 0.508)
			(layers "B.Cu" "B.Mask" "B.Paste")
			(net "A_P5V_SCALED")
		)
		(zone
			(layer "B.Cu")
			(hatch none 0.5)
			(connect_pads
				(clearance 0)
			)
			(min_thickness 0.25)
			(keepout
				(tracks allowed)
				(vias not_allowed)
				(pads allowed)
				(copperpour not_allowed)
				(footprints allowed)
			)
			(placement
				(enabled no)
				(sheetname "")
			)
			(fill
				(thermal_gap 0.5)
				(thermal_bridge_width 0.5)
				(island_removal_mode 0)
			)
			(polygon
				(pts
					(xy 409.3845 -20.066) (xy 409.3845 -19.558) (xy 409.7655 -19.558) (xy 409.7655 -20.066)
				)
			)
		)
		(zone
			(layer "B.Cu")
			(hatch none 0.5)
			(connect_pads
				(clearance 0)
			)
			(min_thickness 0.25)
			(keepout
				(tracks not_allowed)
				(vias allowed)
				(pads allowed)
				(copperpour not_allowed)
				(footprints allowed)
			)
			(placement
				(enabled no)
				(sheetname "")
			)
			(fill
				(thermal_gap 0.5)
				(thermal_bridge_width 0.5)
				(island_removal_mode 0)
			)
			(polygon
				(pts
					(xy 409.7655 -20.066) (xy 409.7655 -19.558) (xy 409.3845 -19.558) (xy 409.3845 -20.066)
				)
			)
		)
	)
	(footprint ""
		(layer "B.Cu")
		(at 442.6712 -15.5702 -90)
		(property "Reference" "R1U43"
			(at 0 0 90)
			(layer "B.SilkS")
			(hide yes)
			(effects
				(font
					(size 1.27 1.27)
				)
				(justify mirror)
			)
		)
		(property "Value" "*"
			(at -0.064008 -4.108196 270)
			(unlocked yes)
			(layer "B.Fab")
			(hide yes)
			(effects
				(font
					(size 1.27 1.016)
					(thickness 0.1524)
				)
				(justify mirror)
			)
		)
		(property "Device Type" "374R2F-1-GP_SMD-RG-374R2F-1-GPA"
			(at -0.064008 -5.632196 270)
			(unlocked yes)
			(layer "B.Fab")
			(hide yes)
			(effects
				(font
					(size 1.27 1.016)
					(thickness 0.1524)
				)
				(justify mirror)
			)
		)
		(duplicate_pad_numbers_are_jumpers no)
		(fp_line
			(start -0.508 -0.9398)
			(end 0.508 -0.9398)
			(stroke
				(width 0.1524)
				(type default)
			)
			(layer "B.SilkS")
		)
		(fp_line
			(start 0.508 -0.9398)
			(end 0.508 0.9398)
			(stroke
				(width 0.1524)
				(type default)
			)
			(layer "B.SilkS")
		)
		(fp_rect
			(start 0.508 0.9398)
			(end -0.508 -0.9398)
			(stroke
				(width 0)
				(type default)
			)
			(fill no)
			(layer "B.CrtYd")
		)
		(fp_rect
			(start 0.508 0.9398)
			(end -0.508 -0.9398)
			(stroke
				(width 0)
				(type default)
			)
			(fill no)
			(layer "B.Fab")
		)
		(pad "1" smd custom
			(at 0 -0.4445 90)
			(size 0.1397 0.1397)
			(layers "B.Cu" "B.Mask" "B.Paste")
			(net "P3V3")
			(options
				(clearance outline)
				(anchor circle)
			)
			(primitives
				(gr_poly
					(pts
						(arc
							(start -0.1778 0.2794)
							(mid -0.249642 0.249642)
							(end -0.2794 0.1778)
						)
						(arc
							(start -0.2794 -0.1778)
							(mid -0.249642 -0.249642)
							(end -0.1778 -0.2794)
						)
						(arc
							(start 0.1778 -0.2794)
							(mid 0.249642 -0.249642)
							(end 0.2794 -0.1778)
						)
						(arc
							(start 0.2794 0.1778)
							(mid 0.249642 0.249642)
							(end 0.1778 0.2794)
						)
					)
					(width 0)
					(fill yes)
				)
			)
		)
		(pad "2" smd custom
			(at 0 0.4445 90)
			(size 0.1397 0.1397)
			(layers "B.Cu" "B.Mask" "B.Paste")
			(net "P0V7_GTL2014_2")
			(options
				(clearance outline)
				(anchor circle)
			)
			(primitives
				(gr_poly
					(pts
						(arc
							(start -0.1778 0.2794)
							(mid -0.249642 0.249642)
							(end -0.2794 0.1778)
						)
						(arc
							(start -0.2794 -0.1778)
							(mid -0.249642 -0.249642)
							(end -0.1778 -0.2794)
						)
						(arc
							(start 0.1778 -0.2794)
							(mid 0.249642 -0.249642)
							(end 0.2794 -0.1778)
						)
						(arc
							(start 0.2794 0.1778)
							(mid 0.249642 0.249642)
							(end 0.1778 0.2794)
						)
					)
					(width 0)
					(fill yes)
				)
			)
		)
	)
	(footprint ""
		(layer "B.Cu")
		(at 24.257 -85.9028 -90)
		(property "Reference" "R9P6"
			(at 0 0 90)
			(layer "B.SilkS")
			(hide yes)
			(effects
				(font
					(size 1.27 1.27)
				)
				(justify mirror)
			)
		)
		(property "Value" ""
			(at 0 0 90)
			(layer "B.Fab")
			(effects
				(font
					(size 1.27 1.27)
				)
				(justify mirror)
			)
		)
		(duplicate_pad_numbers_are_jumpers no)
		(fp_poly
			(pts
				(xy 0.2794 -0.1016) (xy -0.2794 -0.1016) (xy -0.2794 0.9906) (xy 0.2794 0.9906)
			)
			(stroke
				(width 0)
				(type default)
			)
			(fill no)
			(layer "B.CrtYd")
		)
		(fp_line
			(start -0.2794 0.9906)
			(end -0.2794 -0.1016)
			(stroke
				(width 0.1)
				(type default)
			)
			(layer "B.Fab")
		)
		(fp_line
			(start 0.2794 0.9906)
			(end -0.2794 0.9906)
			(stroke
				(width 0.1)
				(type default)
			)
			(layer "B.Fab")
		)
		(fp_line
			(start -0.2794 -0.1016)
			(end 0.2794 -0.1016)
			(stroke
				(width 0.1)
				(type default)
			)
			(layer "B.Fab")
		)
		(fp_line
			(start 0.2794 -0.1016)
			(end 0.2794 0.9906)
			(stroke
				(width 0.1)
				(type default)
			)
			(layer "B.Fab")
		)
		(pad "1" smd rect
			(at 0 0 90)
			(size 0.508 0.508)
			(layers "B.Cu" "B.Mask" "B.Paste")
			(net "P3V3_STBY")
		)
		(pad "2" smd rect
			(at 0 0.889 90)
			(size 0.508 0.508)
			(layers "B.Cu" "B.Mask" "B.Paste")
			(net "FM_UV_ADR_TRIGGER_N")
		)
		(zone
			(layer "B.Cu")
			(hatch none 0.5)
			(connect_pads
				(clearance 0)
			)
			(min_thickness 0.25)
			(keepout
				(tracks not_allowed)
				(vias allowed)
				(pads allowed)
				(copperpour not_allowed)
				(footprints allowed)
			)
			(placement
				(enabled no)
				(sheetname "")
			)
			(fill
				(thermal_gap 0.5)
				(thermal_bridge_width 0.5)
				(island_removal_mode 0)
			)
			(polygon
				(pts
					(xy 23.622 -85.6488) (xy 23.622 -86.1568) (xy 24.003 -86.1568) (xy 24.003 -85.6488)
				)
			)
		)
		(zone
			(layer "B.Cu")
			(hatch none 0.5)
			(connect_pads
				(clearance 0)
			)
			(min_thickness 0.25)
			(keepout
				(tracks allowed)
				(vias not_allowed)
				(pads allowed)
				(copperpour not_allowed)
				(footprints allowed)
			)
			(placement
				(enabled no)
				(sheetname "")
			)
			(fill
				(thermal_gap 0.5)
				(thermal_bridge_width 0.5)
				(island_removal_mode 0)
			)
			(polygon
				(pts
					(xy 24.003 -85.6488) (xy 24.003 -86.1568) (xy 23.622 -86.1568) (xy 23.622 -85.6488)
				)
			)
		)
	)
	(footprint ""
		(layer "B.Cu")
		(at 368.935 -103.632 -90)
		(property "Reference" "C3N28"
			(at 0 0 90)
			(layer "B.SilkS")
			(hide yes)
			(effects
				(font
					(size 1.27 1.27)
				)
				(justify mirror)
			)
		)
		(property "Value" ""
			(at 0 0 90)
			(layer "B.Fab")
			(effects
				(font
					(size 1.27 1.27)
				)
				(justify mirror)
			)
		)
		(duplicate_pad_numbers_are_jumpers no)
		(fp_poly
			(pts
				(xy 0.4953 -0.2032) (xy -0.4953 -0.2032) (xy -0.4953 1.6002) (xy 0.4953 1.6002)
			)
			(stroke
				(width 0)
				(type default)
			)
			(fill no)
			(layer "B.CrtYd")
		)
		(fp_line
			(start -0.4953 1.6002)
			(end 0.4953 1.6002)
			(stroke
				(width 0.1)
				(type default)
			)
			(layer "B.Fab")
		)
		(fp_line
			(start 0.4953 1.6002)
			(end 0.4953 -0.2032)
			(stroke
				(width 0.1)
				(type default)
			)
			(layer "B.Fab")
		)
		(fp_line
			(start -0.4953 -0.2032)
			(end -0.4953 1.6002)
			(stroke
				(width 0.1)
				(type default)
			)
			(layer "B.Fab")
		)
		(fp_line
			(start 0.4953 -0.2032)
			(end -0.4953 -0.2032)
			(stroke
				(width 0.1)
				(type default)
			)
			(layer "B.Fab")
		)
		(pad "1" smd rect
			(at 0 0 90)
			(size 0.762 0.889)
			(layers "B.Cu" "B.Mask" "B.Paste")
			(net "PVNN_PCH_STBY")
		)
		(pad "2" smd rect
			(at 0 1.397 90)
			(size 0.762 0.889)
			(layers "B.Cu" "B.Mask" "B.Paste")
			(net "GND")
		)
		(zone
			(layer "B.Cu")
			(hatch none 0.5)
			(connect_pads
				(clearance 0)
			)
			(min_thickness 0.25)
			(keepout
				(tracks not_allowed)
				(vias allowed)
				(pads allowed)
				(copperpour not_allowed)
				(footprints allowed)
			)
			(placement
				(enabled no)
				(sheetname "")
			)
			(fill
				(thermal_gap 0.5)
				(thermal_bridge_width 0.5)
				(island_removal_mode 0)
			)
			(polygon
				(pts
					(xy 368.4905 -103.251) (xy 368.4905 -104.013) (xy 367.9825 -104.013) (xy 367.9825 -103.251)
				)
			)
		)
	)
)
